FILE_TYPE = CONNECTIVITY;
{Allegro Design Entry HDL 16.6-p007 (v16-6-112F) 10/10/2012}
"PAGE_NUMBER" = 26;
0"NC";
1"M_D_DQS_DP<17:0>";
2"M_D_DQS_DN<17:0>";
3"M_D_MA<17:0>";
4"M_D_BA<1:0>";
5"M_D_BG<1:0>";
6"M_D_CKE<3:0>";
7"M_D_CS_N<7:0>";
8"M_D_ODT<3:0>";
9"M_D_DQ<63:0>";
10"M_D_CLK_DN<3:0>";
11"M_D_CLK_DP<3:0>";
12"M_D_ECC<7:0>";
13"M_D_DQS_DN<7>";
14"M_D_DQ<55>";
15"M_D_ECC<1>";
16"M_D_DQ<41>";
17"M_D_DQS_DP<2>";
18"M_D_DQ<28>";
19"M_D_DQ<52>";
20"M_D_DQ<30>";
21"M_D_ODT<2>";
22"M_D_DQ<34>";
23"M_D_DQ<32>";
24"M_D_DQS_DP<17>";
25"M_D_PAR";
26"M_D_DQ<29>";
27"M_D_DQ<5>";
28"M_D_C<2>";
29"M_D_ECC<0>";
30"M_D_ECC<2>";
31"M_D_ECC<3>";
32"M_D_ECC<4>";
33"M_D_ECC<5>";
34"M_D_ECC<6>";
35"M_D_ECC<7>";
36"M_D_DQ<0>";
37"M_D_DQ<1>";
38"M_D_DQ<2>";
39"M_D_DQ<3>";
40"M_D_DQ<4>";
41"M_D_DQ<6>";
42"M_D_DQ<7>";
43"M_D_DQ<8>";
44"M_D_DQ<9>";
45"M_D_DQ<10>";
46"M_D_CLK_DP<0>";
47"M_D_CLK_DP<1>";
48"M_D_CLK_DP<2>";
49"M_D_CLK_DP<3>";
50"M_D_CLK_DN<0>";
51"M_D_CLK_DN<1>";
52"M_D_CLK_DN<2>";
53"M_D_CLK_DN<3>";
54"M_D_DQ<11>";
55"M_D_DQ<12>";
56"M_D_DQ<13>";
57"M_D_DQ<14>";
58"M_D_DQ<15>";
59"M_D_DQ<16>";
60"M_D_DQ<17>";
61"M_D_DQ<18>";
62"M_D_DQ<19>";
63"M_D_DQ<20>";
64"M_D_DQ<21>";
65"M_D_DQ<22>";
66"M_D_DQ<23>";
67"M_D_DQ<24>";
68"M_D_DQ<25>";
69"M_D_DQ<26>";
70"M_D_DQ<27>";
71"M_D_DQ<31>";
72"M_D_DQ<33>";
73"M_D_DQ<35>";
74"M_D_DQ<36>";
75"M_D_DQ<37>";
76"M_D_DQ<38>";
77"M_D_DQ<39>";
78"M_D_DQ<40>";
79"M_D_DQ<42>";
80"M_D_DQ<43>";
81"M_D_DQ<44>";
82"M_D_DQ<45>";
83"M_D_DQ<46>";
84"M_D_DQ<47>";
85"M_D_DQ<48>";
86"M_D_DQ<49>";
87"M_D_DQ<50>";
88"M_D_DQ<51>";
89"M_D_DQ<53>";
90"M_D_DQ<54>";
91"M_D_DQ<56>";
92"M_D_DQ<57>";
93"M_D_DQ<58>";
94"M_D_DQ<59>";
95"M_D_DQ<60>";
96"M_D_DQ<61>";
97"M_D_DQ<62>";
98"M_D_DQ<63>";
99"M_D_ODT<0>";
100"M_D_ODT<1>";
101"M_D_ODT<3>";
102"M_D_MA<0>";
103"M_D_MA<1>";
104"M_D_MA<2>";
105"M_D_CS_N<0>";
106"M_D_CS_N<1>";
107"M_D_CS_N<2>";
108"M_D_CS_N<3>";
109"M_D_CS_N<4>";
110"M_D_CS_N<5>";
111"M_D_CS_N<6>";
112"M_D_CS_N<7>";
113"M_D_CKE<0>";
114"M_D_CKE<1>";
115"M_D_CKE<2>";
116"M_D_CKE<3>";
117"M_D_BG<0>";
118"M_D_BG<1>";
119"M_D_BA<0>";
120"M_D_BA<1>";
121"M_D_MA<3>";
122"M_D_MA<4>";
123"M_D_MA<5>";
124"M_D_MA<6>";
125"M_D_MA<7>";
126"M_D_MA<8>";
127"M_D_MA<9>";
128"M_D_MA<10>";
129"M_D_MA<11>";
130"M_D_MA<12>";
131"M_D_MA<13>";
132"M_D_MA<14>";
133"M_D_MA<15>";
134"M_D_MA<16>";
135"M_D_MA<17>";
136"M_D_DQS_DP<0>";
137"M_D_DQS_DP<1>";
138"M_D_DQS_DP<3>";
139"M_D_DQS_DP<4>";
140"M_D_DQS_DP<5>";
141"M_D_DQS_DN<0>";
142"M_D_DQS_DN<1>";
143"M_D_DQS_DN<2>";
144"M_D_DQS_DN<3>";
145"M_D_DQS_DN<4>";
146"M_D_DQS_DN<5>";
147"M_D_DQS_DN<6>";
148"M_D_DQS_DN<8>";
149"M_D_DQS_DN<9>";
150"M_D_DQS_DN<10>";
151"M_D_DQS_DN<11>";
152"M_D_DQS_DN<12>";
153"M_D_DQS_DN<13>";
154"M_D_DQS_DN<14>";
155"M_D_DQS_DN<15>";
156"M_D_DQS_DN<16>";
157"M_D_DQS_DN<17>";
158"M_D_ALERT_N";
159"M_D_ACT_N";
160"M_D_DQS_DP<6>";
161"M_D_DQS_DP<7>";
162"M_D_DQS_DP<8>";
163"M_D_DQS_DP<9>";
164"M_D_DQS_DP<10>";
165"M_D_DQS_DP<11>";
166"M_D_DQS_DP<12>";
167"M_D_DQS_DP<13>";
168"M_D_DQS_DP<14>";
169"M_D_DQS_DP<15>";
170"M_D_DQS_DP<16>";
%"TAP"
"6","(-5500,875)","0","mstr_standard","I10";
;
CDS_LIB"mstr_standard"
BODY_TYPE"PLUMBING"
HDL_TAP"TRUE";
"B \NAC \NWC"11;
"S \NAC"
BN"1"47;
%"TAP"
"6","(-2775,1525)","2","mstr_standard","I100";
;
CDS_LIB"mstr_standard"
BODY_TYPE"PLUMBING"
HDL_TAP"TRUE";
"B \NAC \NWC"8;
"S \NAC"
BN"2"21;
%"TAP"
"6","(-2775,1575)","2","mstr_standard","I101";
;
CDS_LIB"mstr_standard"
BODY_TYPE"PLUMBING"
HDL_TAP"TRUE";
"B \NAC \NWC"8;
"S \NAC"
BN"3"101;
%"TAP"
"6","(-2775,1475)","2","mstr_standard","I102";
;
CDS_LIB"mstr_standard"
BODY_TYPE"PLUMBING"
HDL_TAP"TRUE";
"B \NAC \NWC"8;
"S \NAC"
BN"1"100;
%"TAP"
"6","(-2775,1675)","2","mstr_standard","I103";
;
CDS_LIB"mstr_standard"
BODY_TYPE"PLUMBING"
HDL_TAP"TRUE";
"B \NAC \NWC"6;
"S \NAC"
BN"0"113;
%"TAP"
"6","(-2775,1725)","2","mstr_standard","I104";
;
CDS_LIB"mstr_standard"
BODY_TYPE"PLUMBING"
HDL_TAP"TRUE";
"B \NAC \NWC"6;
"S \NAC"
BN"1"114;
%"TAP"
"6","(-2775,1775)","2","mstr_standard","I105";
;
CDS_LIB"mstr_standard"
BODY_TYPE"PLUMBING"
HDL_TAP"TRUE";
"B \NAC \NWC"6;
"S \NAC"
BN"2"115;
%"TAP"
"6","(-2775,1825)","2","mstr_standard","I106";
;
CDS_LIB"mstr_standard"
BODY_TYPE"PLUMBING"
HDL_TAP"TRUE";
"B \NAC \NWC"6;
"S \NAC"
BN"3"116;
%"TAP"
"6","(-2775,1925)","2","mstr_standard","I107";
;
CDS_LIB"mstr_standard"
BODY_TYPE"PLUMBING"
HDL_TAP"TRUE";
"B \NAC \NWC"3;
"S \NAC"
BN"0"102;
%"TAP"
"6","(-2775,1975)","2","mstr_standard","I108";
;
CDS_LIB"mstr_standard"
BODY_TYPE"PLUMBING"
HDL_TAP"TRUE";
"B \NAC \NWC"3;
"S \NAC"
BN"1"103;
%"TAP"
"6","(-2775,2075)","2","mstr_standard","I109";
;
CDS_LIB"mstr_standard"
BODY_TYPE"PLUMBING"
HDL_TAP"TRUE";
"B \NAC \NWC"3;
"S \NAC"
BN"3"121;
%"TAP"
"6","(-5500,925)","0","mstr_standard","I11";
;
CDS_LIB"mstr_standard"
BODY_TYPE"PLUMBING"
HDL_TAP"TRUE";
"B \NAC \NWC"11;
"S \NAC"
BN"2"48;
%"TAP"
"6","(-2775,2025)","2","mstr_standard","I110";
;
CDS_LIB"mstr_standard"
BODY_TYPE"PLUMBING"
HDL_TAP"TRUE";
"B \NAC \NWC"3;
"S \NAC"
BN"2"104;
%"TAP"
"6","(-2775,2125)","2","mstr_standard","I111";
;
CDS_LIB"mstr_standard"
BODY_TYPE"PLUMBING"
HDL_TAP"TRUE";
"B \NAC \NWC"3;
"S \NAC"
BN"4"122;
%"TAP"
"6","(-2775,2225)","2","mstr_standard","I112";
;
CDS_LIB"mstr_standard"
BODY_TYPE"PLUMBING"
HDL_TAP"TRUE";
"B \NAC \NWC"3;
"S \NAC"
BN"6"124;
%"TAP"
"6","(-2775,2175)","2","mstr_standard","I113";
;
CDS_LIB"mstr_standard"
BODY_TYPE"PLUMBING"
HDL_TAP"TRUE";
"B \NAC \NWC"3;
"S \NAC"
BN"5"123;
%"TAP"
"6","(-2775,2275)","2","mstr_standard","I114";
;
CDS_LIB"mstr_standard"
BODY_TYPE"PLUMBING"
HDL_TAP"TRUE";
"B \NAC \NWC"3;
"S \NAC"
BN"7"125;
%"TAP"
"6","(-2775,2325)","2","mstr_standard","I115";
;
CDS_LIB"mstr_standard"
BODY_TYPE"PLUMBING"
HDL_TAP"TRUE";
"B \NAC \NWC"3;
"S \NAC"
BN"8"126;
%"TAP"
"6","(-2775,2375)","2","mstr_standard","I116";
;
CDS_LIB"mstr_standard"
BODY_TYPE"PLUMBING"
HDL_TAP"TRUE";
"B \NAC \NWC"3;
"S \NAC"
BN"9"127;
%"TAP"
"6","(-2775,2425)","2","mstr_standard","I117";
;
CDS_LIB"mstr_standard"
BODY_TYPE"PLUMBING"
HDL_TAP"TRUE";
"B \NAC \NWC"3;
"S \NAC"
BN"10"128;
%"TAP"
"6","(-2775,2475)","2","mstr_standard","I118";
;
CDS_LIB"mstr_standard"
BODY_TYPE"PLUMBING"
HDL_TAP"TRUE";
"B \NAC \NWC"3;
"S \NAC"
BN"11"129;
%"TAP"
"6","(-2775,2575)","2","mstr_standard","I119";
;
CDS_LIB"mstr_standard"
BODY_TYPE"PLUMBING"
HDL_TAP"TRUE";
"B \NAC \NWC"3;
"S \NAC"
BN"13"131;
%"TAP"
"6","(-5500,975)","0","mstr_standard","I12";
;
CDS_LIB"mstr_standard"
BODY_TYPE"PLUMBING"
HDL_TAP"TRUE";
"B \NAC \NWC"11;
"S \NAC"
BN"3"49;
%"TAP"
"6","(-2775,2525)","2","mstr_standard","I120";
;
CDS_LIB"mstr_standard"
BODY_TYPE"PLUMBING"
HDL_TAP"TRUE";
"B \NAC \NWC"3;
"S \NAC"
BN"12"130;
%"TAP"
"6","(-2775,2675)","2","mstr_standard","I121";
;
CDS_LIB"mstr_standard"
BODY_TYPE"PLUMBING"
HDL_TAP"TRUE";
"B \NAC \NWC"3;
"S \NAC"
BN"15"133;
%"TAP"
"6","(-2775,2725)","2","mstr_standard","I122";
;
CDS_LIB"mstr_standard"
BODY_TYPE"PLUMBING"
HDL_TAP"TRUE";
"B \NAC \NWC"3;
"S \NAC"
BN"16"134;
%"TAP"
"6","(-2775,2625)","2","mstr_standard","I123";
;
CDS_LIB"mstr_standard"
BODY_TYPE"PLUMBING"
HDL_TAP"TRUE";
"B \NAC \NWC"3;
"S \NAC"
BN"14"132;
%"TAP"
"6","(-2775,2775)","2","mstr_standard","I124";
;
CDS_LIB"mstr_standard"
BODY_TYPE"PLUMBING"
HDL_TAP"TRUE";
"B \NAC \NWC"3;
"S \NAC"
BN"17"135;
%"TAP"
"6","(-2775,2925)","2","mstr_standard","I125";
;
CDS_LIB"mstr_standard"
BODY_TYPE"PLUMBING"
HDL_TAP"TRUE";
"B \NAC \NWC"2;
"S \NAC"
BN"1"142;
%"TAP"
"6","(-2775,2975)","2","mstr_standard","I126";
;
CDS_LIB"mstr_standard"
BODY_TYPE"PLUMBING"
HDL_TAP"TRUE";
"B \NAC \NWC"2;
"S \NAC"
BN"2"143;
%"TAP"
"6","(-2775,2875)","2","mstr_standard","I127";
;
CDS_LIB"mstr_standard"
BODY_TYPE"PLUMBING"
HDL_TAP"TRUE";
"B \NAC \NWC"2;
"S \NAC"
BN"0"141;
%"TAP"
"6","(-2775,3025)","2","mstr_standard","I128";
;
CDS_LIB"mstr_standard"
BODY_TYPE"PLUMBING"
HDL_TAP"TRUE";
"B \NAC \NWC"2;
"S \NAC"
BN"3"144;
%"TAP"
"6","(-2775,3075)","2","mstr_standard","I129";
;
CDS_LIB"mstr_standard"
BODY_TYPE"PLUMBING"
HDL_TAP"TRUE";
"B \NAC \NWC"2;
"S \NAC"
BN"4"145;
%"TAP"
"6","(-5500,1075)","0","mstr_standard","I13";
;
CDS_LIB"mstr_standard"
BODY_TYPE"PLUMBING"
HDL_TAP"TRUE";
"B \NAC \NWC"12;
"S \NAC"
BN"0"29;
%"TAP"
"6","(-2775,3125)","2","mstr_standard","I130";
;
CDS_LIB"mstr_standard"
BODY_TYPE"PLUMBING"
HDL_TAP"TRUE";
"B \NAC \NWC"2;
"S \NAC"
BN"5"146;
%"TAP"
"6","(-2775,3175)","2","mstr_standard","I131";
;
CDS_LIB"mstr_standard"
BODY_TYPE"PLUMBING"
HDL_TAP"TRUE";
"B \NAC \NWC"2;
"S \NAC"
BN"6"147;
%"TAP"
"6","(-2775,3225)","2","mstr_standard","I132";
;
CDS_LIB"mstr_standard"
BODY_TYPE"PLUMBING"
HDL_TAP"TRUE";
"B \NAC \NWC"2;
"S \NAC"
BN"7"13;
%"TAP"
"6","(-2775,3275)","2","mstr_standard","I133";
;
CDS_LIB"mstr_standard"
BODY_TYPE"PLUMBING"
HDL_TAP"TRUE";
"B \NAC \NWC"2;
"S \NAC"
BN"8"148;
%"TAP"
"6","(-2775,3325)","2","mstr_standard","I134";
;
CDS_LIB"mstr_standard"
BODY_TYPE"PLUMBING"
HDL_TAP"TRUE";
"B \NAC \NWC"2;
"S \NAC"
BN"9"149;
%"TAP"
"6","(-2775,3375)","2","mstr_standard","I135";
;
CDS_LIB"mstr_standard"
BODY_TYPE"PLUMBING"
HDL_TAP"TRUE";
"B \NAC \NWC"2;
"S \NAC"
BN"10"150;
%"TAP"
"6","(-2775,3475)","2","mstr_standard","I136";
;
CDS_LIB"mstr_standard"
BODY_TYPE"PLUMBING"
HDL_TAP"TRUE";
"B \NAC \NWC"2;
"S \NAC"
BN"12"152;
%"TAP"
"6","(-2775,3425)","2","mstr_standard","I137";
;
CDS_LIB"mstr_standard"
BODY_TYPE"PLUMBING"
HDL_TAP"TRUE";
"B \NAC \NWC"2;
"S \NAC"
BN"11"151;
%"TAP"
"6","(-2775,3575)","2","mstr_standard","I138";
;
CDS_LIB"mstr_standard"
BODY_TYPE"PLUMBING"
HDL_TAP"TRUE";
"B \NAC \NWC"2;
"S \NAC"
BN"14"154;
%"TAP"
"6","(-2775,3625)","2","mstr_standard","I139";
;
CDS_LIB"mstr_standard"
BODY_TYPE"PLUMBING"
HDL_TAP"TRUE";
"B \NAC \NWC"2;
"S \NAC"
BN"15"155;
%"TAP"
"6","(-5500,1125)","0","mstr_standard","I14";
;
CDS_LIB"mstr_standard"
BODY_TYPE"PLUMBING"
HDL_TAP"TRUE";
"B \NAC \NWC"12;
"S \NAC"
BN"1"15;
%"TAP"
"6","(-2775,3525)","2","mstr_standard","I140";
;
CDS_LIB"mstr_standard"
BODY_TYPE"PLUMBING"
HDL_TAP"TRUE";
"B \NAC \NWC"2;
"S \NAC"
BN"13"153;
%"TAP"
"6","(-2775,3725)","2","mstr_standard","I141";
;
CDS_LIB"mstr_standard"
BODY_TYPE"PLUMBING"
HDL_TAP"TRUE";
"B \NAC \NWC"2;
"S \NAC"
BN"17"157;
%"TAP"
"6","(-2775,3675)","2","mstr_standard","I142";
;
CDS_LIB"mstr_standard"
BODY_TYPE"PLUMBING"
HDL_TAP"TRUE";
"B \NAC \NWC"2;
"S \NAC"
BN"16"156;
%"TAP"
"6","(-2775,3875)","2","mstr_standard","I143";
;
CDS_LIB"mstr_standard"
BODY_TYPE"PLUMBING"
HDL_TAP"TRUE";
"B \NAC \NWC"1;
"S \NAC"
BN"1"137;
%"TAP"
"6","(-2775,3825)","2","mstr_standard","I144";
;
CDS_LIB"mstr_standard"
BODY_TYPE"PLUMBING"
HDL_TAP"TRUE";
"B \NAC \NWC"1;
"S \NAC"
BN"0"136;
%"TAP"
"6","(-2775,3925)","2","mstr_standard","I145";
;
CDS_LIB"mstr_standard"
BODY_TYPE"PLUMBING"
HDL_TAP"TRUE";
"B \NAC \NWC"1;
"S \NAC"
BN"2"17;
%"TAP"
"6","(-2775,3975)","2","mstr_standard","I146";
;
CDS_LIB"mstr_standard"
BODY_TYPE"PLUMBING"
HDL_TAP"TRUE";
"B \NAC \NWC"1;
"S \NAC"
BN"3"138;
%"TAP"
"6","(-5500,1175)","0","mstr_standard","I15";
;
CDS_LIB"mstr_standard"
BODY_TYPE"PLUMBING"
HDL_TAP"TRUE";
"B \NAC \NWC"12;
"S \NAC"
BN"2"30;
%"TAP"
"6","(-2775,4025)","2","mstr_standard","I157";
;
CDS_LIB"mstr_standard"
BODY_TYPE"PLUMBING"
HDL_TAP"TRUE";
"B \NAC \NWC"1;
"S \NAC"
BN"4"139;
%"TAP"
"6","(-2775,4125)","2","mstr_standard","I158";
;
CDS_LIB"mstr_standard"
BODY_TYPE"PLUMBING"
HDL_TAP"TRUE";
"B \NAC \NWC"1;
"S \NAC"
BN"6"160;
%"TAP"
"6","(-2775,4075)","2","mstr_standard","I159";
;
CDS_LIB"mstr_standard"
BODY_TYPE"PLUMBING"
HDL_TAP"TRUE";
"B \NAC \NWC"1;
"S \NAC"
BN"5"140;
%"TAP"
"6","(-5500,1275)","0","mstr_standard","I16";
;
CDS_LIB"mstr_standard"
BODY_TYPE"PLUMBING"
HDL_TAP"TRUE";
"B \NAC \NWC"12;
"S \NAC"
BN"4"32;
%"TAP"
"6","(-2775,4175)","2","mstr_standard","I160";
;
CDS_LIB"mstr_standard"
BODY_TYPE"PLUMBING"
HDL_TAP"TRUE";
"B \NAC \NWC"1;
"S \NAC"
BN"7"161;
%"TAP"
"6","(-2775,4275)","2","mstr_standard","I161";
;
CDS_LIB"mstr_standard"
BODY_TYPE"PLUMBING"
HDL_TAP"TRUE";
"B \NAC \NWC"1;
"S \NAC"
BN"9"163;
%"TAP"
"6","(-2775,4225)","2","mstr_standard","I162";
;
CDS_LIB"mstr_standard"
BODY_TYPE"PLUMBING"
HDL_TAP"TRUE";
"B \NAC \NWC"1;
"S \NAC"
BN"8"162;
%"TAP"
"6","(-2775,4325)","2","mstr_standard","I163";
;
CDS_LIB"mstr_standard"
BODY_TYPE"PLUMBING"
HDL_TAP"TRUE";
"B \NAC \NWC"1;
"S \NAC"
BN"10"164;
%"TAP"
"6","(-2775,4375)","2","mstr_standard","I164";
;
CDS_LIB"mstr_standard"
BODY_TYPE"PLUMBING"
HDL_TAP"TRUE";
"B \NAC \NWC"1;
"S \NAC"
BN"11"165;
%"TAP"
"6","(-2775,4425)","2","mstr_standard","I165";
;
CDS_LIB"mstr_standard"
BODY_TYPE"PLUMBING"
HDL_TAP"TRUE";
"B \NAC \NWC"1;
"S \NAC"
BN"12"166;
%"TAP"
"6","(-2775,4525)","2","mstr_standard","I166";
;
CDS_LIB"mstr_standard"
BODY_TYPE"PLUMBING"
HDL_TAP"TRUE";
"B \NAC \NWC"1;
"S \NAC"
BN"14"168;
%"TAP"
"6","(-2775,4475)","2","mstr_standard","I167";
;
CDS_LIB"mstr_standard"
BODY_TYPE"PLUMBING"
HDL_TAP"TRUE";
"B \NAC \NWC"1;
"S \NAC"
BN"13"167;
%"TAP"
"6","(-2775,4625)","2","mstr_standard","I168";
;
CDS_LIB"mstr_standard"
BODY_TYPE"PLUMBING"
HDL_TAP"TRUE";
"B \NAC \NWC"1;
"S \NAC"
BN"16"170;
%"TAP"
"6","(-2775,4575)","2","mstr_standard","I169";
;
CDS_LIB"mstr_standard"
BODY_TYPE"PLUMBING"
HDL_TAP"TRUE";
"B \NAC \NWC"1;
"S \NAC"
BN"15"169;
%"TAP"
"6","(-5500,1225)","0","mstr_standard","I17";
;
CDS_LIB"mstr_standard"
BODY_TYPE"PLUMBING"
HDL_TAP"TRUE";
"B \NAC \NWC"12;
"S \NAC"
BN"3"31;
%"TAP"
"6","(-2775,4675)","2","mstr_standard","I170";
;
CDS_LIB"mstr_standard"
BODY_TYPE"PLUMBING"
HDL_TAP"TRUE";
"B \NAC \NWC"1;
"S \NAC"
BN"17"24;
%"SKX_EXT_B"
"6","(-4100,2575)","0","chpset_lib","I172";
;
CDS_SEC"6"
LOCATION"U5D1"
PART_NUMBER"TBD"
MATERIAL"IC"
PACK_TYPE"BGA1"
CDS_LIB"chpset_lib"
SEC_TYPE"BGA1"
SEC"6"
CDS_LOCATION"U5D1"
ROOM"CPU0";
"DDR3_PAR"
$PN"ED53"25;
"DDR3_ODT<0>"
$PN"EE50"99;
"DDR3_ODT<1>"
$PN"EE48"100;
"DDR3_ODT<2>"
$PN"EA50"21;
"DDR3_ODT<3>"
$PN"EA48"101;
"DDR3_MA<0>"
$PN"EB53"102;
"DDR3_MA<1>"
$PN"ED57"103;
"DDR3_MA<2>"
$PN"EE58"104;
"DDR3_MA<3>"
$PN"EB57"121;
"DDR3_MA<4>"
$PN"ED59"122;
"DDR3_MA<5>"
$PN"EA58"123;
"DDR3_MA<6>"
$PN"EE60"124;
"DDR3_MA<7>"
$PN"EA60"125;
"DDR3_MA<8>"
$PN"EB59"126;
"DDR3_MA<9>"
$PN"EF61"127;
"DDR3_MA<10>"
$PN"DW54"128;
"DDR3_MA<11>"
$PN"EB61"129;
"DDR3_MA<12>"
$PN"DT63"130;
"DDR3_MA<13>"
$PN"DW48"131;
"DDR3_MA<14>"
$PN"ED51"132;
"DDR3_MA<15>"
$PN"DV49"133;
"DDR3_MA<16>"
$PN"EA52"134;
"DDR3_MA<17>"
$PN"EA46"135;
"DDR3_ECC<0>"
$PN"DA68"29;
"DDR3_ECC<1>"
$PN"DE68"15;
"DDR3_ECC<2>"
$PN"DB65"30;
"DDR3_ECC<3>"
$PN"DD65"31;
"DDR3_ECC<4>"
$PN"DB69"32;
"DDR3_ECC<5>"
$PN"DD69"33;
"DDR3_ECC<6>"
$PN"DA66"34;
"DDR3_ECC<7>"
$PN"DE66"35;
"DDR3_DQS_DP<0>"
$PN"CV85"136;
"DDR3_DQS_DP<1>"
$PN"DP85"137;
"DDR3_DQS_DP<2>"
$PN"DM81"17;
"DDR3_DQS_DP<3>"
$PN"DT75"138;
"DDR3_DQS_DP<4>"
$PN"EC38"139;
"DDR3_DQS_DP<5>"
$PN"DT35"140;
"DDR3_DQS_DP<6>"
$PN"DT29"160;
"DDR3_DQS_DP<7>"
$PN"DT23"161;
"DDR3_DQS_DP<8>"
$PN"DD67"162;
"DDR3_DQS_DP<9>"
$PN"CP85"163;
"DDR3_DQS_DP<10>"
$PN"DL84"164;
"DDR3_DQS_DP<11>"
$PN"DP79"165;
"DDR3_DQS_DP<12>"
$PN"DM75"166;
"DDR3_DQS_DP<13>"
$PN"DW38"167;
"DDR3_DQS_DP<14>"
$PN"DM35"168;
"DDR3_DQS_DP<15>"
$PN"DP29"169;
"DDR3_DQS_DP<16>"
$PN"DP23"170;
"DDR3_DQS_DP<17>"
$PN"CY67"24;
"DDR3_DQS_DN<0>"
$PN"CU84"141;
"DDR3_DQS_DN<1>"
$PN"DN84"142;
"DDR3_DQS_DN<2>"
$PN"DL82"143;
"DDR3_DQS_DN<3>"
$PN"DV75"144;
"DDR3_DQS_DN<4>"
$PN"EE38"145;
"DDR3_DQS_DN<5>"
$PN"DV35"146;
"DDR3_DQS_DN<6>"
$PN"DV29"147;
"DDR3_DQS_DN<7>"
$PN"DV23"13;
"DDR3_DQS_DN<8>"
$PN"DF67"148;
"DDR3_DQS_DN<9>"
$PN"CR84"149;
"DDR3_DQS_DN<10>"
$PN"DM85"150;
"DDR3_DQS_DN<11>"
$PN"DN80"151;
"DDR3_DQS_DN<12>"
$PN"DP75"152;
"DDR3_DQS_DN<13>"
$PN"EA38"153;
"DDR3_DQS_DN<14>"
$PN"DP35"154;
"DDR3_DQS_DN<15>"
$PN"DM29"155;
"DDR3_DQS_DN<16>"
$PN"DM23"156;
"DDR3_DQS_DN<17>"
$PN"DB67"157;
"DDR3_DQ<0>"
$PN"CN84"36;
"DDR3_DQ<1>"
$PN"CN86"37;
"DDR3_DQ<2>"
$PN"DA86"38;
"DDR3_DQ<3>"
$PN"DA84"39;
"DDR3_DQ<4>"
$PN"CL84"40;
"DDR3_DQ<5>"
$PN"CL86"27;
"DDR3_DQ<6>"
$PN"CW86"41;
"DDR3_DQ<7>"
$PN"CW84"42;
"DDR3_DQ<8>"
$PN"DG84"43;
"DDR3_DQ<9>"
$PN"DH85"44;
"DDR3_DQ<10>"
$PN"DV83"45;
"DDR3_DQ<11>"
$PN"DY83"54;
"DDR3_DQ<12>"
$PN"DD85"55;
"DDR3_DQ<13>"
$PN"DE84"56;
"DDR3_DQ<14>"
$PN"DR84"57;
"DDR3_DQ<15>"
$PN"DV85"58;
"DDR3_DQ<16>"
$PN"DM79"59;
"DDR3_DQ<17>"
$PN"DK81"60;
"DDR3_DQ<18>"
$PN"DT81"61;
"DDR3_DQ<19>"
$PN"DR82"62;
"DDR3_DQ<20>"
$PN"DK79"63;
"DDR3_DQ<21>"
$PN"DJ80"64;
"DDR3_DQ<22>"
$PN"DR80"65;
"DDR3_DQ<23>"
$PN"DN82"66;
"DDR3_DQ<24>"
$PN"DN76"67;
"DDR3_DQ<25>"
$PN"DU76"68;
"DDR3_DQ<26>"
$PN"DP73"69;
"DDR3_DQ<27>"
$PN"DT73"70;
"DDR3_DQ<28>"
$PN"DP77"18;
"DDR3_DQ<29>"
$PN"DT77"26;
"DDR3_DQ<30>"
$PN"DN74"20;
"DDR3_DQ<31>"
$PN"DU74"71;
"DDR3_DQ<32>"
$PN"EC40"23;
"DDR3_DQ<33>"
$PN"ED39"72;
"DDR3_DQ<34>"
$PN"EA36"22;
"DDR3_DQ<35>"
$PN"EC36"73;
"DDR3_DQ<36>"
$PN"DY39"74;
"DDR3_DQ<37>"
$PN"EA40"75;
"DDR3_DQ<38>"
$PN"DY37"76;
"DDR3_DQ<39>"
$PN"ED37"77;
"DDR3_DQ<40>"
$PN"DN36"78;
"DDR3_DQ<41>"
$PN"DU36"16;
"DDR3_DQ<42>"
$PN"DP33"79;
"DDR3_DQ<43>"
$PN"DT33"80;
"DDR3_DQ<44>"
$PN"DP37"81;
"DDR3_DQ<45>"
$PN"DT37"82;
"DDR3_DQ<46>"
$PN"DN34"83;
"DDR3_DQ<47>"
$PN"DU34"84;
"DDR3_DQ<48>"
$PN"DN30"85;
"DDR3_DQ<49>"
$PN"DU30"86;
"DDR3_DQ<50>"
$PN"DP27"87;
"DDR3_DQ<51>"
$PN"DT27"88;
"DDR3_DQ<52>"
$PN"DP31"19;
"DDR3_DQ<53>"
$PN"DT31"89;
"DDR3_DQ<54>"
$PN"DN28"90;
"DDR3_DQ<55>"
$PN"DU28"14;
"DDR3_DQ<56>"
$PN"DN24"91;
"DDR3_DQ<57>"
$PN"DU24"92;
"DDR3_DQ<58>"
$PN"DY21"93;
"DDR3_DQ<59>"
$PN"EB21"94;
"DDR3_DQ<60>"
$PN"DP25"95;
"DDR3_DQ<61>"
$PN"DT25"96;
"DDR3_DQ<62>"
$PN"EC22"97;
"DDR3_DQ<63>"
$PN"DW22"98;
"DDR3_CS_N<0>"
$PN"EF51"105;
"DDR3_CS_N<1>"
$PN"ED49"106;
"DDR3_CS_N<2>"
$PN"ED47"107;
"DDR3_CS_N<3>"
$PN"EB47"108;
"DDR3_CS_N<4>"
$PN"EB51"109;
"DDR3_CS_N<5>"
$PN"EB49"110;
"DDR3_CS_N<6>"
$PN"DV45"111;
"DDR3_CS_N<7>"
$PN"EB45"112;
"DDR3_CLK_DP<0>"
$PN"EB55"46;
"DDR3_CLK_DP<1>"
$PN"EE54"47;
"DDR3_CLK_DP<2>"
$PN"EA56"48;
"DDR3_CLK_DP<3>"
$PN"EE56"49;
"DDR3_CLK_DN<0>"
$PN"ED55"50;
"DDR3_CLK_DN<1>"
$PN"EF55"51;
"DDR3_CLK_DN<2>"
$PN"DW56"52;
"DDR3_CLK_DN<3>"
$PN"EF57"53;
"DDR3_CKE<0>"
$PN"EE62"113;
"DDR3_CKE<1>"
$PN"EF63"114;
"DDR3_CKE<2>"
$PN"EA62"115;
"DDR3_CKE<3>"
$PN"EB63"116;
"DDR3_CID<2>"
$PN"DV47"28;
"DDR3_BG<0>"
$PN"ED61"117;
"DDR3_BG<1>"
$PN"DW62"118;
"DDR3_BA<0>"
$PN"EE52"119;
"DDR3_BA<1>"
$PN"EA54"120;
"DDR3_ALERT_N"
$PN"ED63"158;
"DDR3_ACT_N"
$PN"DW60"159;
%"TAP"
"6","(-5500,1325)","0","mstr_standard","I18";
;
CDS_LIB"mstr_standard"
BODY_TYPE"PLUMBING"
HDL_TAP"TRUE";
"B \NAC \NWC"12;
"S \NAC"
BN"5"33;
%"TAP"
"6","(-5500,1375)","0","mstr_standard","I19";
;
CDS_LIB"mstr_standard"
BODY_TYPE"PLUMBING"
HDL_TAP"TRUE";
"B \NAC \NWC"12;
"S \NAC"
BN"6"34;
%"TAP"
"6","(-5500,1425)","0","mstr_standard","I20";
;
CDS_LIB"mstr_standard"
BODY_TYPE"PLUMBING"
HDL_TAP"TRUE";
"B \NAC \NWC"12;
"S \NAC"
BN"7"35;
%"TAP"
"6","(-5500,1525)","0","mstr_standard","I21";
;
CDS_LIB"mstr_standard"
BODY_TYPE"PLUMBING"
HDL_TAP"TRUE";
"B \NAC \NWC"9;
"S \NAC"
BN"0"36;
%"TAP"
"6","(-5500,1575)","0","mstr_standard","I22";
;
CDS_LIB"mstr_standard"
BODY_TYPE"PLUMBING"
HDL_TAP"TRUE";
"B \NAC \NWC"9;
"S \NAC"
BN"1"37;
%"TAP"
"6","(-5500,1625)","0","mstr_standard","I23";
;
CDS_LIB"mstr_standard"
BODY_TYPE"PLUMBING"
HDL_TAP"TRUE";
"B \NAC \NWC"9;
"S \NAC"
BN"2"38;
%"TAP"
"6","(-5500,1675)","0","mstr_standard","I24";
;
CDS_LIB"mstr_standard"
BODY_TYPE"PLUMBING"
HDL_TAP"TRUE";
"B \NAC \NWC"9;
"S \NAC"
BN"3"39;
%"TAP"
"6","(-5500,1725)","0","mstr_standard","I25";
;
CDS_LIB"mstr_standard"
BODY_TYPE"PLUMBING"
HDL_TAP"TRUE";
"B \NAC \NWC"9;
"S \NAC"
BN"4"40;
%"TAP"
"6","(-5500,1775)","0","mstr_standard","I26";
;
CDS_LIB"mstr_standard"
BODY_TYPE"PLUMBING"
HDL_TAP"TRUE";
"B \NAC \NWC"9;
"S \NAC"
BN"5"27;
%"TAP"
"6","(-5500,1825)","0","mstr_standard","I27";
;
CDS_LIB"mstr_standard"
BODY_TYPE"PLUMBING"
HDL_TAP"TRUE";
"B \NAC \NWC"9;
"S \NAC"
BN"6"41;
%"TAP"
"6","(-5500,1925)","0","mstr_standard","I28";
;
CDS_LIB"mstr_standard"
BODY_TYPE"PLUMBING"
HDL_TAP"TRUE";
"B \NAC \NWC"9;
"S \NAC"
BN"8"43;
%"TAP"
"6","(-5500,1875)","0","mstr_standard","I29";
;
CDS_LIB"mstr_standard"
BODY_TYPE"PLUMBING"
HDL_TAP"TRUE";
"B \NAC \NWC"9;
"S \NAC"
BN"7"42;
%"TAP"
"6","(-5500,1975)","0","mstr_standard","I31";
;
CDS_LIB"mstr_standard"
BODY_TYPE"PLUMBING"
HDL_TAP"TRUE";
"B \NAC \NWC"9;
"S \NAC"
BN"9"44;
%"TAP"
"6","(-5500,2025)","0","mstr_standard","I32";
;
CDS_LIB"mstr_standard"
BODY_TYPE"PLUMBING"
HDL_TAP"TRUE";
"B \NAC \NWC"9;
"S \NAC"
BN"10"45;
%"TAP"
"6","(-5500,2075)","0","mstr_standard","I33";
;
CDS_LIB"mstr_standard"
BODY_TYPE"PLUMBING"
HDL_TAP"TRUE";
"B \NAC \NWC"9;
"S \NAC"
BN"11"54;
%"TAP"
"6","(-5500,2125)","0","mstr_standard","I34";
;
CDS_LIB"mstr_standard"
BODY_TYPE"PLUMBING"
HDL_TAP"TRUE";
"B \NAC \NWC"9;
"S \NAC"
BN"12"55;
%"TAP"
"6","(-5500,2175)","0","mstr_standard","I35";
;
CDS_LIB"mstr_standard"
BODY_TYPE"PLUMBING"
HDL_TAP"TRUE";
"B \NAC \NWC"9;
"S \NAC"
BN"13"56;
%"TAP"
"6","(-5500,2225)","0","mstr_standard","I36";
;
CDS_LIB"mstr_standard"
BODY_TYPE"PLUMBING"
HDL_TAP"TRUE";
"B \NAC \NWC"9;
"S \NAC"
BN"14"57;
%"TAP"
"6","(-5500,2275)","0","mstr_standard","I37";
;
CDS_LIB"mstr_standard"
BODY_TYPE"PLUMBING"
HDL_TAP"TRUE";
"B \NAC \NWC"9;
"S \NAC"
BN"15"58;
%"TAP"
"6","(-5500,2325)","0","mstr_standard","I38";
;
CDS_LIB"mstr_standard"
BODY_TYPE"PLUMBING"
HDL_TAP"TRUE";
"B \NAC \NWC"9;
"S \NAC"
BN"16"59;
%"TAP"
"6","(-5500,2375)","0","mstr_standard","I39";
;
CDS_LIB"mstr_standard"
BODY_TYPE"PLUMBING"
HDL_TAP"TRUE";
"B \NAC \NWC"9;
"S \NAC"
BN"17"60;
%"TAP"
"6","(-5500,2425)","0","mstr_standard","I40";
;
CDS_LIB"mstr_standard"
BODY_TYPE"PLUMBING"
HDL_TAP"TRUE";
"B \NAC \NWC"9;
"S \NAC"
BN"18"61;
%"TAP"
"6","(-5500,2475)","0","mstr_standard","I41";
;
CDS_LIB"mstr_standard"
BODY_TYPE"PLUMBING"
HDL_TAP"TRUE";
"B \NAC \NWC"9;
"S \NAC"
BN"19"62;
%"TAP"
"6","(-5500,2525)","0","mstr_standard","I42";
;
CDS_LIB"mstr_standard"
BODY_TYPE"PLUMBING"
HDL_TAP"TRUE";
"B \NAC \NWC"9;
"S \NAC"
BN"20"63;
%"TAP"
"6","(-5500,2575)","0","mstr_standard","I43";
;
CDS_LIB"mstr_standard"
BODY_TYPE"PLUMBING"
HDL_TAP"TRUE";
"B \NAC \NWC"9;
"S \NAC"
BN"21"64;
%"TAP"
"6","(-5500,2625)","0","mstr_standard","I44";
;
CDS_LIB"mstr_standard"
BODY_TYPE"PLUMBING"
HDL_TAP"TRUE";
"B \NAC \NWC"9;
"S \NAC"
BN"22"65;
%"TAP"
"6","(-5500,2675)","0","mstr_standard","I45";
;
CDS_LIB"mstr_standard"
BODY_TYPE"PLUMBING"
HDL_TAP"TRUE";
"B \NAC \NWC"9;
"S \NAC"
BN"23"66;
%"TAP"
"6","(-5500,2725)","0","mstr_standard","I46";
;
CDS_LIB"mstr_standard"
BODY_TYPE"PLUMBING"
HDL_TAP"TRUE";
"B \NAC \NWC"9;
"S \NAC"
BN"24"67;
%"TAP"
"6","(-5500,2825)","0","mstr_standard","I47";
;
CDS_LIB"mstr_standard"
BODY_TYPE"PLUMBING"
HDL_TAP"TRUE";
"B \NAC \NWC"9;
"S \NAC"
BN"26"69;
%"TAP"
"6","(-5500,2775)","0","mstr_standard","I48";
;
CDS_LIB"mstr_standard"
BODY_TYPE"PLUMBING"
HDL_TAP"TRUE";
"B \NAC \NWC"9;
"S \NAC"
BN"25"68;
%"TAP"
"6","(-5500,2875)","0","mstr_standard","I49";
;
CDS_LIB"mstr_standard"
BODY_TYPE"PLUMBING"
HDL_TAP"TRUE";
"B \NAC \NWC"9;
"S \NAC"
BN"27"70;
%"TAP"
"6","(-5500,625)","0","mstr_standard","I5";
;
CDS_LIB"mstr_standard"
BODY_TYPE"PLUMBING"
HDL_TAP"TRUE";
"B \NAC \NWC"10;
"S \NAC"
BN"0"50;
%"TAP"
"6","(-5500,2925)","0","mstr_standard","I50";
;
CDS_LIB"mstr_standard"
BODY_TYPE"PLUMBING"
HDL_TAP"TRUE";
"B \NAC \NWC"9;
"S \NAC"
BN"28"18;
%"TAP"
"6","(-5500,2975)","0","mstr_standard","I51";
;
CDS_LIB"mstr_standard"
BODY_TYPE"PLUMBING"
HDL_TAP"TRUE";
"B \NAC \NWC"9;
"S \NAC"
BN"29"26;
%"TAP"
"6","(-5500,3075)","0","mstr_standard","I52";
;
CDS_LIB"mstr_standard"
BODY_TYPE"PLUMBING"
HDL_TAP"TRUE";
"B \NAC \NWC"9;
"S \NAC"
BN"31"71;
%"TAP"
"6","(-5500,3025)","0","mstr_standard","I53";
;
CDS_LIB"mstr_standard"
BODY_TYPE"PLUMBING"
HDL_TAP"TRUE";
"B \NAC \NWC"9;
"S \NAC"
BN"30"20;
%"TAP"
"6","(-5500,3125)","0","mstr_standard","I54";
;
CDS_LIB"mstr_standard"
BODY_TYPE"PLUMBING"
HDL_TAP"TRUE";
"B \NAC \NWC"9;
"S \NAC"
BN"32"23;
%"TAP"
"6","(-5500,3175)","0","mstr_standard","I55";
;
CDS_LIB"mstr_standard"
BODY_TYPE"PLUMBING"
HDL_TAP"TRUE";
"B \NAC \NWC"9;
"S \NAC"
BN"33"72;
%"TAP"
"6","(-5500,3225)","0","mstr_standard","I56";
;
CDS_LIB"mstr_standard"
BODY_TYPE"PLUMBING"
HDL_TAP"TRUE";
"B \NAC \NWC"9;
"S \NAC"
BN"34"22;
%"TAP"
"6","(-5500,3325)","0","mstr_standard","I57";
;
CDS_LIB"mstr_standard"
BODY_TYPE"PLUMBING"
HDL_TAP"TRUE";
"B \NAC \NWC"9;
"S \NAC"
BN"36"74;
%"TAP"
"6","(-5500,3275)","0","mstr_standard","I58";
;
CDS_LIB"mstr_standard"
BODY_TYPE"PLUMBING"
HDL_TAP"TRUE";
"B \NAC \NWC"9;
"S \NAC"
BN"35"73;
%"TAP"
"6","(-5500,3375)","0","mstr_standard","I59";
;
CDS_LIB"mstr_standard"
BODY_TYPE"PLUMBING"
HDL_TAP"TRUE";
"B \NAC \NWC"9;
"S \NAC"
BN"37"75;
%"TAP"
"6","(-5500,675)","0","mstr_standard","I6";
;
CDS_LIB"mstr_standard"
BODY_TYPE"PLUMBING"
HDL_TAP"TRUE";
"B \NAC \NWC"10;
"S \NAC"
BN"1"51;
%"TAP"
"6","(-5500,3425)","0","mstr_standard","I60";
;
CDS_LIB"mstr_standard"
BODY_TYPE"PLUMBING"
HDL_TAP"TRUE";
"B \NAC \NWC"9;
"S \NAC"
BN"38"76;
%"TAP"
"6","(-5500,3475)","0","mstr_standard","I61";
;
CDS_LIB"mstr_standard"
BODY_TYPE"PLUMBING"
HDL_TAP"TRUE";
"B \NAC \NWC"9;
"S \NAC"
BN"39"77;
%"TAP"
"6","(-5500,3525)","0","mstr_standard","I62";
;
CDS_LIB"mstr_standard"
BODY_TYPE"PLUMBING"
HDL_TAP"TRUE";
"B \NAC \NWC"9;
"S \NAC"
BN"40"78;
%"TAP"
"6","(-5500,3575)","0","mstr_standard","I63";
;
CDS_LIB"mstr_standard"
BODY_TYPE"PLUMBING"
HDL_TAP"TRUE";
"B \NAC \NWC"9;
"S \NAC"
BN"41"16;
%"TAP"
"6","(-5500,3625)","0","mstr_standard","I64";
;
CDS_LIB"mstr_standard"
BODY_TYPE"PLUMBING"
HDL_TAP"TRUE";
"B \NAC \NWC"9;
"S \NAC"
BN"42"79;
%"TAP"
"6","(-5500,3675)","0","mstr_standard","I65";
;
CDS_LIB"mstr_standard"
BODY_TYPE"PLUMBING"
HDL_TAP"TRUE";
"B \NAC \NWC"9;
"S \NAC"
BN"43"80;
%"TAP"
"6","(-5500,3725)","0","mstr_standard","I66";
;
CDS_LIB"mstr_standard"
BODY_TYPE"PLUMBING"
HDL_TAP"TRUE";
"B \NAC \NWC"9;
"S \NAC"
BN"44"81;
%"TAP"
"6","(-5500,3775)","0","mstr_standard","I67";
;
CDS_LIB"mstr_standard"
BODY_TYPE"PLUMBING"
HDL_TAP"TRUE";
"B \NAC \NWC"9;
"S \NAC"
BN"45"82;
%"TAP"
"6","(-5500,3825)","0","mstr_standard","I68";
;
CDS_LIB"mstr_standard"
BODY_TYPE"PLUMBING"
HDL_TAP"TRUE";
"B \NAC \NWC"9;
"S \NAC"
BN"46"83;
%"TAP"
"6","(-5500,3875)","0","mstr_standard","I69";
;
CDS_LIB"mstr_standard"
BODY_TYPE"PLUMBING"
HDL_TAP"TRUE";
"B \NAC \NWC"9;
"S \NAC"
BN"47"84;
%"TAP"
"6","(-5500,775)","0","mstr_standard","I7";
;
CDS_LIB"mstr_standard"
BODY_TYPE"PLUMBING"
HDL_TAP"TRUE";
"B \NAC \NWC"10;
"S \NAC"
BN"3"53;
%"TAP"
"6","(-5500,3925)","0","mstr_standard","I70";
;
CDS_LIB"mstr_standard"
BODY_TYPE"PLUMBING"
HDL_TAP"TRUE";
"B \NAC \NWC"9;
"S \NAC"
BN"48"85;
%"TAP"
"6","(-5500,3975)","0","mstr_standard","I71";
;
CDS_LIB"mstr_standard"
BODY_TYPE"PLUMBING"
HDL_TAP"TRUE";
"B \NAC \NWC"9;
"S \NAC"
BN"49"86;
%"TAP"
"6","(-5500,4025)","0","mstr_standard","I73";
;
CDS_LIB"mstr_standard"
BODY_TYPE"PLUMBING"
HDL_TAP"TRUE";
"B \NAC \NWC"9;
"S \NAC"
BN"50"87;
%"TAP"
"6","(-5500,4075)","0","mstr_standard","I74";
;
CDS_LIB"mstr_standard"
BODY_TYPE"PLUMBING"
HDL_TAP"TRUE";
"B \NAC \NWC"9;
"S \NAC"
BN"51"88;
%"TAP"
"6","(-5500,4125)","0","mstr_standard","I75";
;
CDS_LIB"mstr_standard"
BODY_TYPE"PLUMBING"
HDL_TAP"TRUE";
"B \NAC \NWC"9;
"S \NAC"
BN"52"19;
%"TAP"
"6","(-5500,4175)","0","mstr_standard","I76";
;
CDS_LIB"mstr_standard"
BODY_TYPE"PLUMBING"
HDL_TAP"TRUE";
"B \NAC \NWC"9;
"S \NAC"
BN"53"89;
%"TAP"
"6","(-5500,4225)","0","mstr_standard","I77";
;
CDS_LIB"mstr_standard"
BODY_TYPE"PLUMBING"
HDL_TAP"TRUE";
"B \NAC \NWC"9;
"S \NAC"
BN"54"90;
%"TAP"
"6","(-5500,4275)","0","mstr_standard","I78";
;
CDS_LIB"mstr_standard"
BODY_TYPE"PLUMBING"
HDL_TAP"TRUE";
"B \NAC \NWC"9;
"S \NAC"
BN"55"14;
%"TAP"
"6","(-5500,4325)","0","mstr_standard","I79";
;
CDS_LIB"mstr_standard"
BODY_TYPE"PLUMBING"
HDL_TAP"TRUE";
"B \NAC \NWC"9;
"S \NAC"
BN"56"91;
%"TAP"
"6","(-5500,725)","0","mstr_standard","I8";
;
CDS_LIB"mstr_standard"
BODY_TYPE"PLUMBING"
HDL_TAP"TRUE";
"B \NAC \NWC"10;
"S \NAC"
BN"2"52;
%"TAP"
"6","(-5500,4375)","0","mstr_standard","I80";
;
CDS_LIB"mstr_standard"
BODY_TYPE"PLUMBING"
HDL_TAP"TRUE";
"B \NAC \NWC"9;
"S \NAC"
BN"57"92;
%"TAP"
"6","(-5500,4425)","0","mstr_standard","I81";
;
CDS_LIB"mstr_standard"
BODY_TYPE"PLUMBING"
HDL_TAP"TRUE";
"B \NAC \NWC"9;
"S \NAC"
BN"58"93;
%"TAP"
"6","(-5500,4475)","0","mstr_standard","I82";
;
CDS_LIB"mstr_standard"
BODY_TYPE"PLUMBING"
HDL_TAP"TRUE";
"B \NAC \NWC"9;
"S \NAC"
BN"59"94;
%"TAP"
"6","(-5500,4525)","0","mstr_standard","I83";
;
CDS_LIB"mstr_standard"
BODY_TYPE"PLUMBING"
HDL_TAP"TRUE";
"B \NAC \NWC"9;
"S \NAC"
BN"60"95;
%"TAP"
"6","(-5500,4575)","0","mstr_standard","I84";
;
CDS_LIB"mstr_standard"
BODY_TYPE"PLUMBING"
HDL_TAP"TRUE";
"B \NAC \NWC"9;
"S \NAC"
BN"61"96;
%"TAP"
"6","(-5500,4625)","0","mstr_standard","I85";
;
CDS_LIB"mstr_standard"
BODY_TYPE"PLUMBING"
HDL_TAP"TRUE";
"B \NAC \NWC"9;
"S \NAC"
BN"62"97;
%"TAP"
"6","(-5500,4675)","0","mstr_standard","I86";
;
CDS_LIB"mstr_standard"
BODY_TYPE"PLUMBING"
HDL_TAP"TRUE";
"B \NAC \NWC"9;
"S \NAC"
BN"63"98;
%"TAP"
"6","(-2775,725)","2","mstr_standard","I87";
;
CDS_LIB"mstr_standard"
BODY_TYPE"PLUMBING"
HDL_TAP"TRUE";
"B \NAC \NWC"4;
"S \NAC"
BN"0"119;
%"TAP"
"6","(-2775,775)","2","mstr_standard","I88";
;
CDS_LIB"mstr_standard"
BODY_TYPE"PLUMBING"
HDL_TAP"TRUE";
"B \NAC \NWC"4;
"S \NAC"
BN"1"120;
%"TAP"
"6","(-2775,875)","2","mstr_standard","I89";
;
CDS_LIB"mstr_standard"
BODY_TYPE"PLUMBING"
HDL_TAP"TRUE";
"B \NAC \NWC"5;
"S \NAC"
BN"1"118;
%"TAP"
"6","(-5500,825)","0","mstr_standard","I9";
;
CDS_LIB"mstr_standard"
BODY_TYPE"PLUMBING"
HDL_TAP"TRUE";
"B \NAC \NWC"11;
"S \NAC"
BN"0"46;
%"TAP"
"6","(-2775,825)","2","mstr_standard","I90";
;
CDS_LIB"mstr_standard"
BODY_TYPE"PLUMBING"
HDL_TAP"TRUE";
"B \NAC \NWC"5;
"S \NAC"
BN"0"117;
%"TAP"
"6","(-2775,1025)","2","mstr_standard","I91";
;
CDS_LIB"mstr_standard"
BODY_TYPE"PLUMBING"
HDL_TAP"TRUE";
"B \NAC \NWC"7;
"S \NAC"
BN"1"106;
%"TAP"
"6","(-2775,975)","2","mstr_standard","I92";
;
CDS_LIB"mstr_standard"
BODY_TYPE"PLUMBING"
HDL_TAP"TRUE";
"B \NAC \NWC"7;
"S \NAC"
BN"0"105;
%"TAP"
"6","(-2775,1075)","2","mstr_standard","I93";
;
CDS_LIB"mstr_standard"
BODY_TYPE"PLUMBING"
HDL_TAP"TRUE";
"B \NAC \NWC"7;
"S \NAC"
BN"2"107;
%"TAP"
"6","(-2775,1175)","2","mstr_standard","I94";
;
CDS_LIB"mstr_standard"
BODY_TYPE"PLUMBING"
HDL_TAP"TRUE";
"B \NAC \NWC"7;
"S \NAC"
BN"4"109;
%"TAP"
"6","(-2775,1125)","2","mstr_standard","I95";
;
CDS_LIB"mstr_standard"
BODY_TYPE"PLUMBING"
HDL_TAP"TRUE";
"B \NAC \NWC"7;
"S \NAC"
BN"3"108;
%"TAP"
"6","(-2775,1325)","2","mstr_standard","I96";
;
CDS_LIB"mstr_standard"
BODY_TYPE"PLUMBING"
HDL_TAP"TRUE";
"B \NAC \NWC"7;
"S \NAC"
BN"7"112;
%"TAP"
"6","(-2775,1225)","2","mstr_standard","I97";
;
CDS_LIB"mstr_standard"
BODY_TYPE"PLUMBING"
HDL_TAP"TRUE";
"B \NAC \NWC"7;
"S \NAC"
BN"5"110;
%"TAP"
"6","(-2775,1275)","2","mstr_standard","I98";
;
CDS_LIB"mstr_standard"
BODY_TYPE"PLUMBING"
HDL_TAP"TRUE";
"B \NAC \NWC"7;
"S \NAC"
BN"6"111;
%"TAP"
"6","(-2775,1425)","2","mstr_standard","I99";
;
CDS_LIB"mstr_standard"
BODY_TYPE"PLUMBING"
HDL_TAP"TRUE";
"B \NAC \NWC"8;
"S \NAC"
BN"0"99;
END.
